# BASEBOARD_FAB2 (Tioga Pass) — schematic netlist excerpt (pin names and nets, part order shuffled) for the footprints in the layout excerpt that follows; sources: Cadence DE-HDL packaged netlist, KiCad conversion of Wiwynn_Tioga_Pass_MB.brd

R8E36  2K15R2F-1-GP  1%  pkg SMD-RG1  page 142 : \1\ = P3V3_STBY ; \2\ = FM_PE_SLOTX24_WAKE_N
C8U8  CAP  100UF 4V 20% X5R  pkg 0805  page 225 : A = PVDDQ_GHJ ; B = GND
C2T23  CAP  0.22UF 16V 10% X7R  pkg 0402  page 185 : A = P3E_PCH_M2_TX_C_DN<3> ; B = P3E_PCH_M2_TX_DN<3>

(kicad_pcb
	(version 20260206)
	(generator "pcbnew")
	(generator_version "10.0")
	(general
		(thickness 1.6)
		(legacy_teardrops no)
	)
	(paper "A4")
	(title_block
		(title "Wiwynn_Tioga_Pass_MB.brd")
		(comment 1 "Tioga Pass / footprints 2602-2604 of 4770")
	)
	(layers
		(0 "F.Cu" signal "TOP")
		(4 "In1.Cu" signal "L2GND")
		(6 "In2.Cu" signal "L3")
		(8 "In3.Cu" signal "L4GND")
		(10 "In4.Cu" signal "L5")
		(12 "In5.Cu" signal "L6GND")
		(14 "In6.Cu" signal "L7VCC")
		(16 "In7.Cu" signal "L8VCC")
		(18 "In8.Cu" signal "L9GND")
		(20 "In9.Cu" signal "L10")
		(22 "In10.Cu" signal "L11GND")
		(24 "In11.Cu" signal "L12")
		(26 "In12.Cu" signal "L13GND")
		(2 "B.Cu" signal "BOTTOM")
		(9 "F.Adhes" user "F.Adhesive")
		(11 "B.Adhes" user "B.Adhesive")
		(13 "F.Paste" user "Package Geometry/Pastemask Top")
		(15 "B.Paste" user "Package Geometry/Pastemask Bottom")
		(5 "F.SilkS" user "Ref Des/Silkscreen Top")
		(7 "B.SilkS" user "Ref Des/Silkscreen Bottom")
		(1 "F.Mask" user "Board Geometry/Soldermask Top")
		(3 "B.Mask" user "Board Geometry/Soldermask Bottom")
		(17 "Dwgs.User" user "User.Drawings")
		(19 "Cmts.User" user "User.Comments")
		(21 "Eco1.User" user "User.Eco1")
		(23 "Eco2.User" user "User.Eco2")
		(25 "Edge.Cuts" user "Board Geometry/Outline")
		(27 "Margin" user)
		(31 "F.CrtYd" user "Package Geometry/Place Bound Top")
		(29 "B.CrtYd" user "Package Geometry/Place Bound Bottom")
		(35 "F.Fab" user "Ref Des/Assembly Top")
		(33 "B.Fab" user "Ref Des/Assembly Bottom")
	)
	(footprint ""
		(layer "B.Cu")
		(at 463.7278 -7.112)
		(property "Reference" "R8E36"
			(at 0 0 0)
			(layer "B.SilkS")
			(hide yes)
			(effects
				(font
					(size 1.27 1.27)
				)
				(justify mirror)
			)
		)
		(property "Value" "*"
			(at -0.064008 -4.108196 0)
			(unlocked yes)
			(layer "B.Fab")
			(hide yes)
			(effects
				(font
					(size 1.27 1.016)
					(thickness 0.1524)
				)
				(justify mirror)
			)
		)
		(property "Device Type" "2K15R2F-1-GP_SMD-RG1-2K15R2F-1A"
			(at -0.064008 -5.632196 0)
			(unlocked yes)
			(layer "B.Fab")
			(hide yes)
			(effects
				(font
					(size 1.27 1.016)
					(thickness 0.1524)
				)
				(justify mirror)
			)
		)
		(duplicate_pad_numbers_are_jumpers no)
		(fp_line
			(start -0.508 -0.9398)
			(end 0.508 -0.9398)
			(stroke
				(width 0.1524)
				(type default)
			)
			(layer "B.SilkS")
		)
		(fp_line
			(start 0.508 -0.9398)
			(end 0.508 0.9398)
			(stroke
				(width 0.1524)
				(type default)
			)
			(layer "B.SilkS")
		)
		(fp_rect
			(start 0.508 0.9398)
			(end -0.508 -0.9398)
			(stroke
				(width 0)
				(type default)
			)
			(fill no)
			(layer "B.CrtYd")
		)
		(fp_rect
			(start 0.508 0.9398)
			(end -0.508 -0.9398)
			(stroke
				(width 0)
				(type default)
			)
			(fill no)
			(layer "B.Fab")
		)
		(pad "1" smd custom
			(at 0 -0.4445 180)
			(size 0.1397 0.1397)
			(layers "B.Cu" "B.Mask" "B.Paste")
			(net "P3V3_STBY")
			(options
				(clearance outline)
				(anchor circle)
			)
			(primitives
				(gr_poly
					(pts
						(arc
							(start -0.1778 0.2794)
							(mid -0.249642 0.249642)
							(end -0.2794 0.1778)
						)
						(arc
							(start -0.2794 -0.1778)
							(mid -0.249642 -0.249642)
							(end -0.1778 -0.2794)
						)
						(arc
							(start 0.1778 -0.2794)
							(mid 0.249642 -0.249642)
							(end 0.2794 -0.1778)
						)
						(arc
							(start 0.2794 0.1778)
							(mid 0.249642 0.249642)
							(end 0.1778 0.2794)
						)
					)
					(width 0)
					(fill yes)
				)
			)
		)
		(pad "2" smd custom
			(at 0 0.4445 180)
			(size 0.1397 0.1397)
			(layers "B.Cu" "B.Mask" "B.Paste")
			(net "FM_PE_SLOTX24_WAKE_N")
			(options
				(clearance outline)
				(anchor circle)
			)
			(primitives
				(gr_poly
					(pts
						(arc
							(start -0.1778 0.2794)
							(mid -0.249642 0.249642)
							(end -0.2794 0.1778)
						)
						(arc
							(start -0.2794 -0.1778)
							(mid -0.249642 -0.249642)
							(end -0.1778 -0.2794)
						)
						(arc
							(start 0.1778 -0.2794)
							(mid 0.249642 -0.249642)
							(end 0.2794 -0.1778)
						)
						(arc
							(start 0.2794 0.1778)
							(mid 0.249642 0.249642)
							(end 0.1778 0.2794)
						)
					)
					(width 0)
					(fill yes)
				)
			)
		)
	)
	(footprint ""
		(layer "B.Cu")
		(at 94.663768 -8.122412 90)
		(property "Reference" "C8U8"
			(at 0 0 90)
			(layer "B.SilkS")
			(hide yes)
			(effects
				(font
					(size 1.27 1.27)
				)
				(justify mirror)
			)
		)
		(property "Value" ""
			(at 0 0 90)
			(layer "B.Fab")
			(effects
				(font
					(size 1.27 1.27)
				)
				(justify mirror)
			)
		)
		(duplicate_pad_numbers_are_jumpers no)
		(fp_poly
			(pts
				(xy 0.7239 -0.2159) (xy -0.7239 -0.2159) (xy -0.7239 1.9939) (xy 0.7239 1.9939)
			)
			(stroke
				(width 0)
				(type default)
			)
			(fill no)
			(layer "B.CrtYd")
		)
		(fp_line
			(start 0.7239 -0.2159)
			(end 0.7239 1.9939)
			(stroke
				(width 0.1)
				(type default)
			)
			(layer "B.Fab")
		)
		(fp_line
			(start -0.7239 -0.2159)
			(end 0.7239 -0.2159)
			(stroke
				(width 0.1)
				(type default)
			)
			(layer "B.Fab")
		)
		(fp_line
			(start 0.7239 1.9939)
			(end -0.7239 1.9939)
			(stroke
				(width 0.1)
				(type default)
			)
			(layer "B.Fab")
		)
		(fp_line
			(start -0.7239 1.9939)
			(end -0.7239 -0.2159)
			(stroke
				(width 0.1)
				(type default)
			)
			(layer "B.Fab")
		)
		(pad "1" smd rect
			(at 0 0 270)
			(size 1.27 1.016)
			(layers "B.Cu" "B.Mask" "B.Paste")
			(net "PVDDQ_GHJ")
		)
		(pad "2" smd rect
			(at 0 1.778 270)
			(size 1.27 1.016)
			(layers "B.Cu" "B.Mask" "B.Paste")
			(net "GND")
		)
		(zone
			(layer "B.Cu")
			(hatch none 0.5)
			(connect_pads
				(clearance 0)
			)
			(min_thickness 0.25)
			(keepout
				(tracks not_allowed)
				(vias allowed)
				(pads allowed)
				(copperpour not_allowed)
				(footprints allowed)
			)
			(placement
				(enabled no)
				(sheetname "")
			)
			(fill
				(thermal_gap 0.5)
				(thermal_bridge_width 0.5)
				(island_removal_mode 0)
			)
			(polygon
				(pts
					(xy 95.171768 -8.757412) (xy 95.171768 -7.487412) (xy 95.933768 -7.487412) (xy 95.933768 -8.757412)
				)
			)
		)
	)
	(footprint ""
		(layer "B.Cu")
		(at 385.217924 -23.869904 90)
		(property "Reference" "C2T23"
			(at 0 0 90)
			(layer "B.SilkS")
			(hide yes)
			(effects
				(font
					(size 1.27 1.27)
				)
				(justify mirror)
			)
		)
		(property "Value" ""
			(at 0 0 90)
			(layer "B.Fab")
			(effects
				(font
					(size 1.27 1.27)
				)
				(justify mirror)
			)
		)
		(duplicate_pad_numbers_are_jumpers no)
		(fp_poly
			(pts
				(xy -0.3048 -0.1016) (xy -0.3048 0.9906) (xy 0.3048 0.9906) (xy 0.3048 -0.1016)
			)
			(stroke
				(width 0)
				(type default)
			)
			(fill no)
			(layer "B.CrtYd")
		)
		(fp_line
			(start 0.3048 -0.1016)
			(end 0.3048 0.9906)
			(stroke
				(width 0.1)
				(type default)
			)
			(layer "B.Fab")
		)
		(fp_line
			(start -0.3048 -0.1016)
			(end 0.3048 -0.1016)
			(stroke
				(width 0.1)
				(type default)
			)
			(layer "B.Fab")
		)
		(fp_line
			(start 0.3048 0.9906)
			(end -0.3048 0.9906)
			(stroke
				(width 0.1)
				(type default)
			)
			(layer "B.Fab")
		)
		(fp_line
			(start -0.3048 0.9906)
			(end -0.3048 -0.1016)
			(stroke
				(width 0.1)
				(type default)
			)
			(layer "B.Fab")
		)
		(pad "1" smd rect
			(at 0 0 270)
			(size 0.508 0.508)
			(layers "B.Cu" "B.Mask" "B.Paste")
			(net "P3E_PCH_M2_TX_C_DN<3>")
		)
		(pad "2" smd rect
			(at 0 0.889 270)
			(size 0.508 0.508)
			(layers "B.Cu" "B.Mask" "B.Paste")
			(net "P3E_PCH_M2_TX_DN<3>")
		)
		(zone
			(layer "B.Cu")
			(hatch none 0.5)
			(connect_pads
				(clearance 0)
			)
			(min_thickness 0.25)
			(keepout
				(tracks allowed)
				(vias not_allowed)
				(pads allowed)
				(copperpour not_allowed)
				(footprints allowed)
			)
			(placement
				(enabled no)
				(sheetname "")
			)
			(fill
				(thermal_gap 0.5)
				(thermal_bridge_width 0.5)
				(island_removal_mode 0)
			)
			(polygon
				(pts
					(xy 385.471924 -24.123904) (xy 385.471924 -23.615904) (xy 385.852924 -23.615904) (xy 385.852924 -24.123904)
				)
			)
		)
		(zone
			(layer "B.Cu")
			(hatch none 0.5)
			(connect_pads
				(clearance 0)
			)
			(min_thickness 0.25)
			(keepout
				(tracks not_allowed)
				(vias allowed)
				(pads allowed)
				(copperpour not_allowed)
				(footprints allowed)
			)
			(placement
				(enabled no)
				(sheetname "")
			)
			(fill
				(thermal_gap 0.5)
				(thermal_bridge_width 0.5)
				(island_removal_mode 0)
			)
			(polygon
				(pts
					(xy 385.852924 -24.123904) (xy 385.852924 -23.615904) (xy 385.471924 -23.615904) (xy 385.471924 -24.123904)
				)
			)
		)
	)
)
